# T6G (Grand Teton) — schematic netlist excerpt (pin names and nets, part order shuffled) for the footprints in the layout excerpt that follows; sources: Cadence DE-HDL packaged netlist, KiCad conversion of 04192023_DAF0TMB3IC0_F0TG_MB_C_brd_V02_OCP.brd

C224  Q_CAP  0.1UF 25V 10% X7R  pkg 0402  page 78 : A = P1V8_AUX ; B = GND
R1012  Q_RES  0 5% CHIP  pkg 0201LF  page 287 : A = RST_RT_CPU0_P1_RESET_N ; B = RST_RT_CPU0_P1_RESET_R_N
C1521  Q_CAP  0.1UF 16V 10% X7R  pkg C0402  page 174 : A = PVDD18_S5_P0 ; B = GND

(kicad_pcb
	(version 20260206)
	(generator "pcbnew")
	(generator_version "10.0")
	(general
		(thickness 1.6)
		(legacy_teardrops no)
	)
	(paper "A4")
	(title_block
		(title "04192023_DAF0TMB3IC0_F0TG_MB_C_brd_V02_OCP.brd")
		(comment 1 "Grand Teton / footprints 3607-3609 of 8354")
	)
	(layers
		(0 "F.Cu" signal "TOP")
		(4 "In1.Cu" signal "GND")
		(6 "In2.Cu" signal "IN1")
		(8 "In3.Cu" signal "GND1")
		(10 "In4.Cu" signal "IN2")
		(12 "In5.Cu" signal "GND2")
		(14 "In6.Cu" signal "IN3")
		(16 "In7.Cu" signal "GND3")
		(18 "In8.Cu" signal "VCC")
		(20 "In9.Cu" signal "VCC1")
		(22 "In10.Cu" signal "GND4")
		(24 "In11.Cu" signal "IN4")
		(26 "In12.Cu" signal "GND5")
		(28 "In13.Cu" signal "IN5")
		(30 "In14.Cu" signal "GND6")
		(32 "In15.Cu" signal "IN6")
		(34 "In16.Cu" signal "GND7")
		(2 "B.Cu" signal "BOTTOM")
		(9 "F.Adhes" user "F.Adhesive")
		(11 "B.Adhes" user "B.Adhesive")
		(13 "F.Paste" user "Package Geometry/Pastemask Top")
		(15 "B.Paste" user "Package Geometry/Pastemask Bottom")
		(5 "F.SilkS" user "Ref Des/Silkscreen Top")
		(7 "B.SilkS" user "Ref Des/Silkscreen Bottom")
		(1 "F.Mask" user "Board Geometry/Soldermask Top")
		(3 "B.Mask" user "Board Geometry/Soldermask Bottom")
		(17 "Dwgs.User" user "User.Drawings")
		(19 "Cmts.User" user "User.Comments")
		(21 "Eco1.User" user "User.Eco1")
		(23 "Eco2.User" user "User.Eco2")
		(25 "Edge.Cuts" user "Board Geometry/Outline")
		(27 "Margin" user)
		(31 "F.CrtYd" user "Package Geometry/Place Bound Top")
		(29 "B.CrtYd" user "Package Geometry/Place Bound Bottom")
		(35 "F.Fab" user "Ref Des/Assembly Top")
		(33 "B.Fab" user "Ref Des/Assembly Bottom")
	)
	(footprint ""
		(layer "F.Cu")
		(at 229.603554 -151.752046 180)
		(property "Reference" "C1521"
			(at 0 0 180)
			(layer "F.SilkS")
			(hide yes)
			(effects
				(font
					(size 1.27 1.27)
				)
			)
		)
		(property "Value" ""
			(at 0 0 180)
			(layer "F.Fab")
			(effects
				(font
					(size 1.27 1.27)
				)
			)
		)
		(duplicate_pad_numbers_are_jumpers no)
		(fp_line
			(start 0.7874 0.4064)
			(end -0.7874 0.4064)
			(stroke
				(width 0.1524)
				(type default)
			)
			(layer "F.SilkS")
		)
		(fp_line
			(start 0.7874 -0.4064)
			(end 0.7874 0.4064)
			(stroke
				(width 0.1524)
				(type default)
			)
			(layer "F.SilkS")
		)
		(fp_line
			(start -0.7874 0.4064)
			(end -0.7874 -0.4064)
			(stroke
				(width 0.1524)
				(type default)
			)
			(layer "F.SilkS")
		)
		(fp_line
			(start -0.7874 -0.4064)
			(end 0.7874 -0.4064)
			(stroke
				(width 0.1524)
				(type default)
			)
			(layer "F.SilkS")
		)
		(fp_line
			(start 0.67945 0.3048)
			(end 0.120396 0.3048)
			(stroke
				(width 0.1)
				(type default)
			)
			(layer "F.Fab")
		)
		(fp_line
			(start 0.67945 -0.3048)
			(end 0.67945 0.3048)
			(stroke
				(width 0.1)
				(type default)
			)
			(layer "F.Fab")
		)
		(fp_line
			(start 0.12065 -0.2794)
			(end 0.12065 -0.3048)
			(stroke
				(width 0.1)
				(type default)
			)
			(layer "F.Fab")
		)
		(fp_line
			(start 0.12065 -0.3048)
			(end 0.67945 -0.3048)
			(stroke
				(width 0.1)
				(type default)
			)
			(layer "F.Fab")
		)
		(fp_line
			(start 0.120396 0.3048)
			(end 0.120396 0.2794)
			(stroke
				(width 0.1)
				(type default)
			)
			(layer "F.Fab")
		)
		(fp_line
			(start 0.120396 0.2794)
			(end -0.12065 0.2794)
			(stroke
				(width 0.1)
				(type default)
			)
			(layer "F.Fab")
		)
		(fp_line
			(start -0.12065 0.3048)
			(end -0.67945 0.3048)
			(stroke
				(width 0.1)
				(type default)
			)
			(layer "F.Fab")
		)
		(fp_line
			(start -0.12065 0.2794)
			(end -0.12065 0.3048)
			(stroke
				(width 0.1)
				(type default)
			)
			(layer "F.Fab")
		)
		(fp_line
			(start -0.12065 -0.2794)
			(end 0.12065 -0.2794)
			(stroke
				(width 0.1)
				(type default)
			)
			(layer "F.Fab")
		)
		(fp_line
			(start -0.12065 -0.305054)
			(end -0.12065 -0.2794)
			(stroke
				(width 0.1)
				(type default)
			)
			(layer "F.Fab")
		)
		(fp_line
			(start -0.67945 0.3048)
			(end -0.67945 -0.305054)
			(stroke
				(width 0.1)
				(type default)
			)
			(layer "F.Fab")
		)
		(fp_line
			(start -0.67945 -0.305054)
			(end -0.12065 -0.305054)
			(stroke
				(width 0.1)
				(type default)
			)
			(layer "F.Fab")
		)
		(pad "1" smd circle
			(at -0.40005 0 180)
			(size 0 0)
			(layers "F.Cu" "F.Mask" "F.Paste")
			(net "PVDD18_S5_P0")
		)
		(pad "2" smd circle
			(at 0.40005 0 180)
			(size 0 0)
			(layers "F.Cu" "F.Mask" "F.Paste")
			(net "GND")
		)
	)
	(footprint ""
		(layer "F.Cu")
		(at 83.878166 -143.785844)
		(property "Reference" "C224"
			(at 0 0 0)
			(layer "F.SilkS")
			(hide yes)
			(effects
				(font
					(size 1.27 1.27)
				)
			)
		)
		(property "Value" ""
			(at 0 0 0)
			(layer "F.Fab")
			(effects
				(font
					(size 1.27 1.27)
				)
			)
		)
		(duplicate_pad_numbers_are_jumpers no)
		(fp_line
			(start -0.7874 -0.4064)
			(end 0.7874 -0.4064)
			(stroke
				(width 0.1524)
				(type default)
			)
			(layer "F.SilkS")
		)
		(fp_line
			(start -0.7874 0.4064)
			(end -0.7874 -0.4064)
			(stroke
				(width 0.1524)
				(type default)
			)
			(layer "F.SilkS")
		)
		(fp_line
			(start 0.7874 -0.4064)
			(end 0.7874 0.4064)
			(stroke
				(width 0.1524)
				(type default)
			)
			(layer "F.SilkS")
		)
		(fp_line
			(start 0.7874 0.4064)
			(end -0.7874 0.4064)
			(stroke
				(width 0.1524)
				(type default)
			)
			(layer "F.SilkS")
		)
		(fp_line
			(start -0.67945 -0.305054)
			(end -0.12065 -0.305054)
			(stroke
				(width 0.1)
				(type default)
			)
			(layer "F.Fab")
		)
		(fp_line
			(start -0.67945 0.3048)
			(end -0.67945 -0.305054)
			(stroke
				(width 0.1)
				(type default)
			)
			(layer "F.Fab")
		)
		(fp_line
			(start -0.12065 -0.305054)
			(end -0.12065 -0.2794)
			(stroke
				(width 0.1)
				(type default)
			)
			(layer "F.Fab")
		)
		(fp_line
			(start -0.12065 -0.2794)
			(end 0.12065 -0.2794)
			(stroke
				(width 0.1)
				(type default)
			)
			(layer "F.Fab")
		)
		(fp_line
			(start -0.12065 0.2794)
			(end -0.12065 0.3048)
			(stroke
				(width 0.1)
				(type default)
			)
			(layer "F.Fab")
		)
		(fp_line
			(start -0.12065 0.3048)
			(end -0.67945 0.3048)
			(stroke
				(width 0.1)
				(type default)
			)
			(layer "F.Fab")
		)
		(fp_line
			(start 0.120396 0.2794)
			(end -0.12065 0.2794)
			(stroke
				(width 0.1)
				(type default)
			)
			(layer "F.Fab")
		)
		(fp_line
			(start 0.120396 0.3048)
			(end 0.120396 0.2794)
			(stroke
				(width 0.1)
				(type default)
			)
			(layer "F.Fab")
		)
		(fp_line
			(start 0.12065 -0.3048)
			(end 0.67945 -0.3048)
			(stroke
				(width 0.1)
				(type default)
			)
			(layer "F.Fab")
		)
		(fp_line
			(start 0.12065 -0.2794)
			(end 0.12065 -0.3048)
			(stroke
				(width 0.1)
				(type default)
			)
			(layer "F.Fab")
		)
		(fp_line
			(start 0.67945 -0.3048)
			(end 0.67945 0.3048)
			(stroke
				(width 0.1)
				(type default)
			)
			(layer "F.Fab")
		)
		(fp_line
			(start 0.67945 0.3048)
			(end 0.120396 0.3048)
			(stroke
				(width 0.1)
				(type default)
			)
			(layer "F.Fab")
		)
		(pad "1" smd circle
			(at -0.40005 0)
			(size 0 0)
			(layers "F.Cu" "F.Mask" "F.Paste")
			(net "P1V8_AUX")
		)
		(pad "2" smd circle
			(at 0.40005 0)
			(size 0 0)
			(layers "F.Cu" "F.Mask" "F.Paste")
			(net "GND")
		)
	)
	(footprint ""
		(layer "F.Cu")
		(at 332.250288 -403.285452 90)
		(property "Reference" "R1012"
			(at 0 0 90)
			(layer "F.SilkS")
			(hide yes)
			(effects
				(font
					(size 1.27 1.27)
				)
			)
		)
		(property "Value" ""
			(at 0 0 90)
			(layer "F.Fab")
			(effects
				(font
					(size 1.27 1.27)
				)
			)
		)
		(duplicate_pad_numbers_are_jumpers no)
		(fp_line
			(start 0.32512 -0.175006)
			(end 0.32512 0.175006)
			(stroke
				(width 0.1)
				(type default)
			)
			(layer "F.Fab")
		)
		(fp_line
			(start -0.32512 -0.175006)
			(end 0.32512 -0.175006)
			(stroke
				(width 0.1)
				(type default)
			)
			(layer "F.Fab")
		)
		(fp_line
			(start 0.32512 0.175006)
			(end -0.32512 0.175006)
			(stroke
				(width 0.1)
				(type default)
			)
			(layer "F.Fab")
		)
		(fp_line
			(start -0.32512 0.175006)
			(end -0.32512 -0.175006)
			(stroke
				(width 0.1)
				(type default)
			)
			(layer "F.Fab")
		)
		(pad "1" smd rect
			(at -0.2667 0 90)
			(size 0.3048 0.381)
			(layers "F.Cu" "F.Mask" "F.Paste")
			(net "RST_RT_CPU0_P1_RESET_N")
		)
		(pad "2" smd rect
			(at 0.2667 0 270)
			(size 0.3048 0.381)
			(layers "F.Cu" "F.Mask" "F.Paste")
			(net "RST_RT_CPU0_P1_RESET_R_N")
		)
	)
)
